(kicad_pcb
	(version 20260206)
	(generator "pcbnew")
	(generator_version "10.0")
	(general
		(thickness 1.6)
		(legacy_teardrops no)
	)
	(paper "A4")
	(title_block
		(title "fcb — Lightning_FCB_BRD.brd")
		(comment 1 "Lightning (Wiwynn / Facebook NVMe JBOF) / footprints 290-293 of 495")
	)
	(layers
		(0 "F.Cu" signal "TOP")
		(4 "In1.Cu" signal "L2GND")
		(6 "In2.Cu" signal "L3VCC")
		(2 "B.Cu" signal "BOTTOM")
		(9 "F.Adhes" user "F.Adhesive")
		(11 "B.Adhes" user "B.Adhesive")
		(13 "F.Paste" user "Package Geometry/Pastemask Top")
		(15 "B.Paste" user "Package Geometry/Pastemask Bottom")
		(5 "F.SilkS" user "Ref Des/Silkscreen Top")
		(7 "B.SilkS" user "Ref Des/Silkscreen Bottom")
		(1 "F.Mask" user "Board Geometry/Soldermask Top")
		(3 "B.Mask" user "Board Geometry/Soldermask Bottom")
		(17 "Dwgs.User" user "User.Drawings")
		(19 "Cmts.User" user "User.Comments")
		(21 "Eco1.User" user "User.Eco1")
		(23 "Eco2.User" user "User.Eco2")
		(25 "Edge.Cuts" user "Board Geometry/Outline")
		(27 "Margin" user)
		(31 "F.CrtYd" user "Package Geometry/Place Bound Top")
		(29 "B.CrtYd" user "Package Geometry/Place Bound Bottom")
		(35 "F.Fab" user "Ref Des/Assembly Top")
		(33 "B.Fab" user "Ref Des/Assembly Bottom")
	)
	(footprint ""
		(layer "F.Cu")
		(at 30.36189 -159.849566 180)
		(property "Reference" "U1"
			(at 0 0 180)
			(layer "F.SilkS")
			(hide yes)
			(effects
				(font
					(size 1.27 1.27)
				)
			)
		)
		(property "Value" "NCT7904D-GP"
			(at -4.064 -8.5852 180)
			(unlocked yes)
			(layer "F.Fab")
			(hide yes)
			(effects
				(font
					(size 1.016 1.016)
					(thickness 0.1524)
				)
			)
		)
		(property "Device Type" "LQFP48H63"
			(at -4.064 -10.3632 180)
			(unlocked yes)
			(layer "F.Fab")
			(hide yes)
			(effects
				(font
					(size 1.016 1.016)
					(thickness 0.1524)
				)
			)
		)
		(duplicate_pad_numbers_are_jumpers no)
		(fp_line
			(start 5.5118 5.5118)
			(end 5.5118 3.0226)
			(stroke
				(width 0.1524)
				(type default)
			)
			(layer "F.SilkS")
		)
		(fp_line
			(start 5.5118 -3.0734)
			(end 5.4864 -3.0734)
			(stroke
				(width 0.1524)
				(type default)
			)
			(layer "F.SilkS")
		)
		(fp_line
			(start 5.5118 -5.5118)
			(end 5.5118 -3.0734)
			(stroke
				(width 0.1524)
				(type default)
			)
			(layer "F.SilkS")
		)
		(fp_line
			(start 5.4864 -3.0734)
			(end 3.048 -5.5118)
			(stroke
				(width 0.1524)
				(type default)
			)
			(layer "F.SilkS")
		)
		(fp_line
			(start 5.1562 1.24968)
			(end 5.9182 1.24968)
			(stroke
				(width 0.1524)
				(type default)
			)
			(layer "F.SilkS")
		)
		(fp_line
			(start 5.1562 -1.24968)
			(end 5.6642 -1.24968)
			(stroke
				(width 0.1524)
				(type default)
			)
			(layer "F.SilkS")
		)
		(fp_line
			(start 3.048 -5.5118)
			(end 5.5118 -5.5118)
			(stroke
				(width 0.1524)
				(type default)
			)
			(layer "F.SilkS")
		)
		(fp_line
			(start 2.9718 5.5118)
			(end 5.5118 5.5118)
			(stroke
				(width 0.1524)
				(type default)
			)
			(layer "F.SilkS")
		)
		(fp_line
			(start 2.25044 5.1562)
			(end 2.25044 5.6642)
			(stroke
				(width 0.1524)
				(type default)
			)
			(layer "F.SilkS")
		)
		(fp_line
			(start 0.75057 -5.1562)
			(end 0.75057 -5.6642)
			(stroke
				(width 0.1524)
				(type default)
			)
			(layer "F.SilkS")
		)
		(fp_line
			(start -0.25019 5.1562)
			(end -0.25019 5.9182)
			(stroke
				(width 0.1524)
				(type default)
			)
			(layer "F.SilkS")
		)
		(fp_line
			(start -1.75006 -5.1562)
			(end -1.75006 -5.9182)
			(stroke
				(width 0.1524)
				(type default)
			)
			(layer "F.SilkS")
		)
		(fp_line
			(start -2.74955 5.1562)
			(end -2.74955 5.6642)
			(stroke
				(width 0.1524)
				(type default)
			)
			(layer "F.SilkS")
		)
		(fp_line
			(start -3.0988 -5.5118)
			(end -5.5118 -5.5118)
			(stroke
				(width 0.1524)
				(type default)
			)
			(layer "F.SilkS")
		)
		(fp_line
			(start -5.1562 0.75057)
			(end -5.9182 0.75057)
			(stroke
				(width 0.1524)
				(type default)
			)
			(layer "F.SilkS")
		)
		(fp_line
			(start -5.1562 -1.75006)
			(end -5.6642 -1.75006)
			(stroke
				(width 0.1524)
				(type default)
			)
			(layer "F.SilkS")
		)
		(fp_line
			(start -5.5118 5.5118)
			(end -2.9972 5.5118)
			(stroke
				(width 0.1524)
				(type default)
			)
			(layer "F.SilkS")
		)
		(fp_line
			(start -5.5118 2.9718)
			(end -5.5118 5.5118)
			(stroke
				(width 0.1524)
				(type default)
			)
			(layer "F.SilkS")
		)
		(fp_line
			(start -5.5118 -5.5118)
			(end -5.5118 -2.9464)
			(stroke
				(width 0.1524)
				(type default)
			)
			(layer "F.SilkS")
		)
		(fp_poly
			(pts
				(xy 5.5118 -3.048) (xy 3.048 -5.5118) (xy 5.5118 -5.5118)
			)
			(stroke
				(width 0)
				(type default)
			)
			(fill no)
			(layer "F.SilkS")
		)
		(fp_poly
			(pts
				(xy 3.0734 -5.5118) (xy 5.5118 -5.5118) (xy 5.5118 -3.1496) (xy 5.4356 -3.1496)
			)
			(stroke
				(width 0)
				(type default)
			)
			(fill yes)
			(layer "F.SilkS")
		)
		(fp_rect
			(start -5.5118 5.5118)
			(end 5.5118 -5.5118)
			(stroke
				(width 0)
				(type default)
			)
			(fill no)
			(layer "F.CrtYd")
		)
		(fp_rect
			(start -5.5118 5.5118)
			(end 5.5118 -5.5118)
			(stroke
				(width 0)
				(type default)
			)
			(fill no)
			(layer "F.Fab")
		)
		(pad "1" smd rect
			(at 2.74955 -4.2418 180)
			(size 0.3048 1.524)
			(layers "F.Cu" "F.Mask" "F.Paste")
			(net "NCT7904_VREF")
		)
		(pad "2" smd rect
			(at 2.25044 -4.2418 180)
			(size 0.3048 1.524)
			(layers "F.Cu" "F.Mask" "F.Paste")
			(net "NCT7904_D1+")
		)
		(pad "3" smd rect
			(at 1.75006 -4.2418 180)
			(size 0.3048 1.524)
			(layers "F.Cu" "F.Mask" "F.Paste")
			(net "NCT7904_D1-")
		)
		(pad "4" smd rect
			(at 1.24968 -4.2418 180)
			(size 0.3048 1.524)
			(layers "F.Cu" "F.Mask" "F.Paste")
			(net "NCT7904_D2+")
		)
		(pad "5" smd rect
			(at 0.75057 -4.2418 180)
			(size 0.3048 1.524)
			(layers "F.Cu" "F.Mask" "F.Paste")
			(net "NCT7904_D2-")
		)
		(pad "6" smd rect
			(at 0.25019 -4.2418 180)
			(size 0.3048 1.524)
			(layers "F.Cu" "F.Mask" "F.Paste")
			(net "NCT7904_VSEN6")
		)
		(pad "7" smd rect
			(at -0.25019 -4.2418 180)
			(size 0.3048 1.524)
			(layers "F.Cu" "F.Mask" "F.Paste")
			(net "NCT7904_VSEN7")
		)
		(pad "8" smd rect
			(at -0.75057 -4.2418 180)
			(size 0.3048 1.524)
			(layers "F.Cu" "F.Mask" "F.Paste")
			(net "NCT7904_VSEN8")
		)
		(pad "9" smd rect
			(at -1.24968 -4.2418 180)
			(size 0.3048 1.524)
			(layers "F.Cu" "F.Mask" "F.Paste")
			(net "NCT7904_VSEN9")
		)
		(pad "10" smd rect
			(at -1.75006 -4.2418 180)
			(size 0.3048 1.524)
			(layers "F.Cu" "F.Mask" "F.Paste")
			(net "NCT7904_VSEN10")
		)
		(pad "11" smd rect
			(at -2.25044 -4.2418 180)
			(size 0.3048 1.524)
			(layers "F.Cu" "F.Mask" "F.Paste")
			(net "NCT7904_VSEN11")
		)
		(pad "12" smd rect
			(at -2.74955 -4.2418 180)
			(size 0.3048 1.524)
			(layers "F.Cu" "F.Mask" "F.Paste")
			(net "NCT7904_VSEN12")
		)
		(pad "13" smd rect
			(at -4.2418 -2.74955 180)
			(size 1.524 0.3048)
			(layers "F.Cu" "F.Mask" "F.Paste")
			(net "NCT7904_VSEN13")
		)
		(pad "14" smd rect
			(at -4.2418 -2.25044 180)
			(size 1.524 0.3048)
			(layers "F.Cu" "F.Mask" "F.Paste")
			(net "NCT7904_VSEN14")
		)
		(pad "15" smd rect
			(at -4.2418 -1.75006 180)
			(size 1.524 0.3048)
			(layers "F.Cu" "F.Mask" "F.Paste")
			(net "NCT7904_3VDD")
		)
		(pad "16" smd rect
			(at -4.2418 -1.24968 180)
			(size 1.524 0.3048)
			(layers "F.Cu" "F.Mask" "F.Paste")
			(net "NCT7904_3VSB")
		)
		(pad "17" smd rect
			(at -4.2418 -0.75057 180)
			(size 1.524 0.3048)
			(layers "F.Cu" "F.Mask" "F.Paste")
			(net "NCT7904_SMI")
		)
		(pad "18" smd rect
			(at -4.2418 -0.25019 180)
			(size 1.524 0.3048)
			(layers "F.Cu" "F.Mask" "F.Paste")
			(net "NCT7904_PROCHOT")
		)
		(pad "19" smd rect
			(at -4.2418 0.25019 180)
			(size 1.524 0.3048)
			(layers "F.Cu" "F.Mask" "F.Paste")
			(net "NCT7904_VSEN1")
		)
		(pad "20" smd rect
			(at -4.2418 0.75057 180)
			(size 1.524 0.3048)
			(layers "F.Cu" "F.Mask" "F.Paste")
			(net "NCT7904_PECI")
		)
		(pad "21" smd rect
			(at -4.2418 1.24968 180)
			(size 1.524 0.3048)
			(layers "F.Cu" "F.Mask" "F.Paste")
			(net "NCT7904_THERMTRIP")
		)
		(pad "22" smd rect
			(at -4.2418 1.75006 180)
			(size 1.524 0.3048)
			(layers "F.Cu" "F.Mask" "F.Paste")
			(net "NCT7904_CLKIN")
		)
		(pad "23" smd rect
			(at -4.2418 2.25044 180)
			(size 1.524 0.3048)
			(layers "F.Cu" "F.Mask" "F.Paste")
			(net "I2C_C_SCL_NCT7904")
		)
		(pad "24" smd rect
			(at -4.2418 2.74955 180)
			(size 1.524 0.3048)
			(layers "F.Cu" "F.Mask" "F.Paste")
			(net "I2C_C_SDA_NCT7904")
		)
		(pad "25" smd rect
			(at -2.74955 4.2418 180)
			(size 0.3048 1.524)
			(layers "F.Cu" "F.Mask" "F.Paste")
			(net "FANIN_1")
		)
		(pad "26" smd rect
			(at -2.25044 4.2418 180)
			(size 0.3048 1.524)
			(layers "F.Cu" "F.Mask" "F.Paste")
			(net "FANIN_2")
		)
		(pad "27" smd rect
			(at -1.75006 4.2418 180)
			(size 0.3048 1.524)
			(layers "F.Cu" "F.Mask" "F.Paste")
			(net "NCT7904_ADR")
		)
		(pad "28" smd rect
			(at -1.24968 4.2418 180)
			(size 0.3048 1.524)
			(layers "F.Cu" "F.Mask" "F.Paste")
			(net "NCT7904_RSTOUT")
		)
		(pad "29" smd rect
			(at -0.75057 4.2418 180)
			(size 0.3048 1.524)
			(layers "F.Cu" "F.Mask" "F.Paste")
			(net "FANIN_11")
		)
		(pad "30" smd rect
			(at -0.25019 4.2418 180)
			(size 0.3048 1.524)
			(layers "F.Cu" "F.Mask" "F.Paste")
			(net "NCT7904D_PWM1")
		)
		(pad "31" smd rect
			(at 0.25019 4.2418 180)
			(size 0.3048 1.524)
			(layers "F.Cu" "F.Mask" "F.Paste")
			(net "FANIN_12")
		)
		(pad "32" smd rect
			(at 0.75057 4.2418 180)
			(size 0.3048 1.524)
			(layers "F.Cu" "F.Mask" "F.Paste")
			(net "NCT7904D_PWM2")
		)
		(pad "33" smd rect
			(at 1.24968 4.2418 180)
			(size 0.3048 1.524)
			(layers "F.Cu" "F.Mask" "F.Paste")
			(net "FANIN_9")
		)
		(pad "34" smd rect
			(at 1.75006 4.2418 180)
			(size 0.3048 1.524)
			(layers "F.Cu" "F.Mask" "F.Paste")
			(net "NCT7904D_PWM3")
		)
		(pad "35" smd rect
			(at 2.25044 4.2418 180)
			(size 0.3048 1.524)
			(layers "F.Cu" "F.Mask" "F.Paste")
			(net "FANIN_10")
		)
		(pad "36" smd rect
			(at 2.74955 4.2418 180)
			(size 0.3048 1.524)
			(layers "F.Cu" "F.Mask" "F.Paste")
			(net "NCT7904D_PWM4")
		)
		(pad "37" smd rect
			(at 4.2418 2.74955 180)
			(size 1.524 0.3048)
			(layers "F.Cu" "F.Mask" "F.Paste")
			(net "FANIN_7")
		)
		(pad "38" smd rect
			(at 4.2418 2.25044 180)
			(size 1.524 0.3048)
			(layers "F.Cu" "F.Mask" "F.Paste")
			(net "FANIN_8")
		)
		(pad "39" smd rect
			(at 4.2418 1.75006 180)
			(size 1.524 0.3048)
			(layers "F.Cu" "F.Mask" "F.Paste")
			(net "FANIN_5")
		)
		(pad "40" smd rect
			(at 4.2418 1.24968 180)
			(size 1.524 0.3048)
			(layers "F.Cu" "F.Mask" "F.Paste")
			(net "FANIN_6")
		)
		(pad "41" smd rect
			(at 4.2418 0.75057 180)
			(size 1.524 0.3048)
			(layers "F.Cu" "F.Mask" "F.Paste")
			(net "FANIN_3")
		)
		(pad "42" smd rect
			(at 4.2418 0.25019 180)
			(size 1.524 0.3048)
			(layers "F.Cu" "F.Mask" "F.Paste")
			(net "FANIN_4")
		)
		(pad "43" smd rect
			(at 4.2418 -0.25019 180)
			(size 1.524 0.3048)
			(layers "F.Cu" "F.Mask" "F.Paste")
			(net "NCT7904_GND")
		)
		(pad "44" smd rect
			(at 4.2418 -0.75057 180)
			(size 1.524 0.3048)
			(layers "F.Cu" "F.Mask" "F.Paste")
			(net "NCT7904_TMPALM")
		)
		(pad "45" smd rect
			(at 4.2418 -1.24968 180)
			(size 1.524 0.3048)
			(layers "F.Cu" "F.Mask" "F.Paste")
			(net "NCT7904_LED")
		)
		(pad "46" smd rect
			(at 4.2418 -1.75006 180)
			(size 1.524 0.3048)
			(layers "F.Cu" "F.Mask" "F.Paste")
			(net "NCT7904_RESET")
		)
		(pad "47" smd rect
			(at 4.2418 -2.25044 180)
			(size 1.524 0.3048)
			(layers "F.Cu" "F.Mask" "F.Paste")
			(net "NCT7904_CASEOPEN")
		)
		(pad "48" smd rect
			(at 4.2418 -2.74955 180)
			(size 1.524 0.3048)
			(layers "F.Cu" "F.Mask" "F.Paste")
			(net "NCT7904_3VSB")
		)
	)
	(footprint ""
		(layer "F.Cu")
		(at 19.9644 -145.4912 180)
		(property "Reference" "PR114"
			(at 0 0 180)
			(layer "F.SilkS")
			(hide yes)
			(effects
				(font
					(size 1.27 1.27)
				)
			)
		)
		(property "Value" "20KR2F-L-GP"
			(at 0.064008 -3.993896 180)
			(unlocked yes)
			(layer "F.Fab")
			(hide yes)
			(effects
				(font
					(size 1.016 1.016)
					(thickness 0.1524)
				)
			)
		)
		(property "Device Type" "R402H16"
			(at 0.064008 -5.517896 180)
			(unlocked yes)
			(layer "F.Fab")
			(hide yes)
			(effects
				(font
					(size 1.016 1.016)
					(thickness 0.1524)
				)
			)
		)
		(duplicate_pad_numbers_are_jumpers no)
		(fp_line
			(start 0.508 -0.9398)
			(end -0.508 -0.9398)
			(stroke
				(width 0.1524)
				(type default)
			)
			(layer "F.SilkS")
		)
		(fp_line
			(start -0.508 -0.9398)
			(end -0.508 0.9398)
			(stroke
				(width 0.1524)
				(type default)
			)
			(layer "F.SilkS")
		)
		(fp_rect
			(start -0.508 0.9398)
			(end 0.508 -0.9398)
			(stroke
				(width 0)
				(type default)
			)
			(fill no)
			(layer "F.CrtYd")
		)
		(fp_rect
			(start -0.508 0.9398)
			(end 0.508 -0.9398)
			(stroke
				(width 0)
				(type default)
			)
			(fill no)
			(layer "F.Fab")
		)
		(pad "1" smd custom
			(at 0 -0.4445 180)
			(size 0.1397 0.1397)
			(layers "F.Cu" "F.Mask" "F.Paste")
			(net "P12VU_2490_PROG")
			(options
				(clearance outline)
				(anchor circle)
			)
			(primitives
				(gr_poly
					(pts
						(arc
							(start -0.1778 -0.2794)
							(mid -0.249642 -0.249642)
							(end -0.2794 -0.1778)
						)
						(arc
							(start -0.2794 0.1778)
							(mid -0.249642 0.249642)
							(end -0.1778 0.2794)
						)
						(arc
							(start 0.1778 0.2794)
							(mid 0.249642 0.249642)
							(end 0.2794 0.1778)
						)
						(arc
							(start 0.2794 -0.1778)
							(mid 0.249642 -0.249642)
							(end 0.1778 -0.2794)
						)
					)
					(width 0)
					(fill yes)
				)
			)
		)
		(pad "2" smd custom
			(at 0 0.4445 180)
			(size 0.1397 0.1397)
			(layers "F.Cu" "F.Mask" "F.Paste")
			(net "GND")
			(options
				(clearance outline)
				(anchor circle)
			)
			(primitives
				(gr_poly
					(pts
						(arc
							(start -0.1778 -0.2794)
							(mid -0.249642 -0.249642)
							(end -0.2794 -0.1778)
						)
						(arc
							(start -0.2794 0.1778)
							(mid -0.249642 0.249642)
							(end -0.1778 0.2794)
						)
						(arc
							(start 0.1778 0.2794)
							(mid 0.249642 0.249642)
							(end 0.2794 0.1778)
						)
						(arc
							(start 0.2794 -0.1778)
							(mid 0.249642 -0.249642)
							(end 0.1778 -0.2794)
						)
					)
					(width 0)
					(fill yes)
				)
			)
		)
	)
	(footprint ""
		(layer "F.Cu")
		(at 19.5834 -266.7254)
		(property "Reference" "F4"
			(at 0 0 0)
			(layer "F.SilkS")
			(hide yes)
			(effects
				(font
					(size 1.27 1.27)
				)
			)
		)
		(property "Value" "FUSE-3A15V-GP"
			(at 0.2286 -10.5918 0)
			(unlocked yes)
			(layer "F.Fab")
			(hide yes)
			(effects
				(font
					(size 1.016 1.016)
					(thickness 0.1524)
				)
			)
		)
		(property "Device Type" "FUSE-7452-UH50"
			(at 0.2286 -12.4968 0)
			(unlocked yes)
			(layer "F.Fab")
			(hide yes)
			(effects
				(font
					(size 1.016 1.016)
					(thickness 0.1524)
				)
			)
		)
		(duplicate_pad_numbers_are_jumpers no)
		(fp_line
			(start -4.9276 -2.921)
			(end 4.9276 -2.921)
			(stroke
				(width 0.1524)
				(type default)
			)
			(layer "F.SilkS")
		)
		(fp_line
			(start -4.9276 2.921)
			(end -4.9276 -2.921)
			(stroke
				(width 0.1524)
				(type default)
			)
			(layer "F.SilkS")
		)
		(fp_line
			(start 4.9276 -2.921)
			(end 4.9276 2.921)
			(stroke
				(width 0.1524)
				(type default)
			)
			(layer "F.SilkS")
		)
		(fp_line
			(start 4.9276 2.921)
			(end -4.9276 2.921)
			(stroke
				(width 0.1524)
				(type default)
			)
			(layer "F.SilkS")
		)
		(fp_poly
			(pts
				(xy -5.08 3.0988) (xy 5.08 3.0988) (xy 5.08 -3.0988) (xy -5.08 -3.0988)
			)
			(stroke
				(width 0)
				(type default)
			)
			(fill no)
			(layer "F.CrtYd")
		)
		(fp_poly
			(pts
				(xy -5.08 -3.0988) (xy 5.08 -3.0988) (xy 5.08 3.0988) (xy -5.08 3.0988)
			)
			(stroke
				(width 0)
				(type default)
			)
			(fill no)
			(layer "F.Fab")
		)
		(pad "1" smd rect
			(at -3.4036 0)
			(size 2.2098 5.2832)
			(layers "F.Cu" "F.Mask" "F.Paste")
			(net "P12V_FAN3")
		)
		(pad "2" smd rect
			(at 3.4036 0)
			(size 2.2098 5.2832)
			(layers "F.Cu" "F.Mask" "F.Paste")
			(net "P12V")
		)
	)
	(footprint ""
		(layer "F.Cu")
		(at 33.909 -374.396)
		(property "Reference" "PC6"
			(at 0 0 0)
			(layer "F.SilkS")
			(hide yes)
			(effects
				(font
					(size 1.27 1.27)
				)
			)
		)
		(property "Value" "SCD022U50V3KX-2-GP"
			(at 0 -2.8194 0)
			(unlocked yes)
			(layer "F.Fab")
			(hide yes)
			(effects
				(font
					(size 1.016 1.016)
					(thickness 0.1524)
				)
			)
		)
		(property "Device Type" "C603"
			(at 0 -4.3434 0)
			(unlocked yes)
			(layer "F.Fab")
			(hide yes)
			(effects
				(font
					(size 1.016 1.016)
					(thickness 0.1524)
				)
			)
		)
		(duplicate_pad_numbers_are_jumpers no)
		(fp_line
			(start 0.508 0)
			(end -0.508 0)
			(stroke
				(width 0.2032)
				(type default)
			)
			(layer "F.SilkS")
		)
		(fp_rect
			(start -0.5842 1.3335)
			(end 0.5842 -1.3335)
			(stroke
				(width 0)
				(type default)
			)
			(fill no)
			(layer "F.CrtYd")
		)
		(fp_rect
			(start -0.5842 1.3335)
			(end 0.5842 -1.3335)
			(stroke
				(width 0)
				(type default)
			)
			(fill no)
			(layer "F.Fab")
		)
		(pad "1" smd custom
			(at 0 -0.762)
			(size 0.2159 0.2159)
			(layers "F.Cu" "F.Mask" "F.Paste")
			(net "ADM1276_GATE_RC")
			(options
				(clearance outline)
				(anchor circle)
			)
			(primitives
				(gr_poly
					(pts
						(arc
							(start -0.3302 -0.4318)
							(mid -0.402042 -0.402042)
							(end -0.4318 -0.3302)
						)
						(arc
							(start -0.4318 0.3302)
							(mid -0.402042 0.402042)
							(end -0.3302 0.4318)
						)
						(arc
							(start 0.3302 0.4318)
							(mid 0.402042 0.402042)
							(end 0.4318 0.3302)
						)
						(arc
							(start 0.4318 -0.3302)
							(mid 0.402042 -0.402042)
							(end 0.3302 -0.4318)
						)
					)
					(width 0)
					(fill yes)
				)
			)
		)
		(pad "2" smd custom
			(at 0 0.762)
			(size 0.2159 0.2159)
			(layers "F.Cu" "F.Mask" "F.Paste")
			(net "GND")
			(options
				(clearance outline)
				(anchor circle)
			)
			(primitives
				(gr_poly
					(pts
						(arc
							(start -0.3302 -0.4318)
							(mid -0.402042 -0.402042)
							(end -0.4318 -0.3302)
						)
						(arc
							(start -0.4318 0.3302)
							(mid -0.402042 0.402042)
							(end -0.3302 0.4318)
						)
						(arc
							(start 0.3302 0.4318)
							(mid 0.402042 0.402042)
							(end 0.4318 0.3302)
						)
						(arc
							(start 0.4318 -0.3302)
							(mid 0.402042 -0.402042)
							(end 0.3302 -0.4318)
						)
					)
					(width 0)
					(fill yes)
				)
			)
		)
	)
)
